# BASEBOARD_FAB2 (Tioga Pass) — schematic netlist excerpt (pin names and nets, part order shuffled) for the footprints in the layout excerpt that follows; sources: Cadence DE-HDL packaged netlist, KiCad conversion of Wiwynn_Tioga_Pass_MB.brd

Q1W6  NPN  MMBT3904 IC  pkg SM  page 89
  B  = FM_ADR_COMPLETE_CPU1_R
  E  = GND
  C  = FM_ADR_COMPLETE_CPU1_N

R10W5  RES  0.0 5% CHIP  pkg 0805  page 251 : A = P12V_FAN ; B = P12V_PUMP
C9W13  CAP  22UF 4V 20% X6S  pkg 0805LF  page 239 : A = P2V5_AUX_BMC ; B = GND

(kicad_pcb
	(version 20260206)
	(generator "pcbnew")
	(generator_version "10.0")
	(general
		(thickness 1.6)
		(legacy_teardrops no)
	)
	(paper "A4")
	(title_block
		(title "Wiwynn_Tioga_Pass_MB.brd")
		(comment 1 "Tioga Pass / footprints 1182-1184 of 4770")
	)
	(layers
		(0 "F.Cu" signal "TOP")
		(4 "In1.Cu" signal "L2GND")
		(6 "In2.Cu" signal "L3")
		(8 "In3.Cu" signal "L4GND")
		(10 "In4.Cu" signal "L5")
		(12 "In5.Cu" signal "L6GND")
		(14 "In6.Cu" signal "L7VCC")
		(16 "In7.Cu" signal "L8VCC")
		(18 "In8.Cu" signal "L9GND")
		(20 "In9.Cu" signal "L10")
		(22 "In10.Cu" signal "L11GND")
		(24 "In11.Cu" signal "L12")
		(26 "In12.Cu" signal "L13GND")
		(2 "B.Cu" signal "BOTTOM")
		(9 "F.Adhes" user "F.Adhesive")
		(11 "B.Adhes" user "B.Adhesive")
		(13 "F.Paste" user "Package Geometry/Pastemask Top")
		(15 "B.Paste" user "Package Geometry/Pastemask Bottom")
		(5 "F.SilkS" user "Ref Des/Silkscreen Top")
		(7 "B.SilkS" user "Ref Des/Silkscreen Bottom")
		(1 "F.Mask" user "Board Geometry/Soldermask Top")
		(3 "B.Mask" user "Board Geometry/Soldermask Bottom")
		(17 "Dwgs.User" user "User.Drawings")
		(19 "Cmts.User" user "User.Comments")
		(21 "Eco1.User" user "User.Eco1")
		(23 "Eco2.User" user "User.Eco2")
		(25 "Edge.Cuts" user "Board Geometry/Outline")
		(27 "Margin" user)
		(31 "F.CrtYd" user "Package Geometry/Place Bound Top")
		(29 "B.CrtYd" user "Package Geometry/Place Bound Bottom")
		(35 "F.Fab" user "Ref Des/Assembly Top")
		(33 "B.Fab" user "Ref Des/Assembly Bottom")
	)
	(footprint ""
		(layer "F.Cu")
		(at 7.333234 -113.840514 90)
		(property "Reference" "R10W5"
			(at 1.47828 0.78994 0)
			(unlocked yes)
			(layer "F.SilkS")
			(effects
				(font
					(size 0.4064 0.254)
					(thickness 0.1524)
				)
			)
		)
		(property "Value" ""
			(at 0 0 90)
			(layer "F.Fab")
			(effects
				(font
					(size 1.27 1.27)
				)
			)
		)
		(duplicate_pad_numbers_are_jumpers no)
		(fp_poly
			(pts
				(xy -0.7239 -0.2159) (xy 0.7239 -0.2159) (xy 0.7239 1.9939) (xy -0.7239 1.9939)
			)
			(stroke
				(width 0)
				(type default)
			)
			(fill no)
			(layer "F.CrtYd")
		)
		(fp_line
			(start 0.7239 -0.2159)
			(end -0.7239 -0.2159)
			(stroke
				(width 0.1)
				(type default)
			)
			(layer "F.Fab")
		)
		(fp_line
			(start -0.7239 -0.2159)
			(end -0.7239 1.9939)
			(stroke
				(width 0.1)
				(type default)
			)
			(layer "F.Fab")
		)
		(fp_line
			(start 0.7239 1.9939)
			(end 0.7239 -0.2159)
			(stroke
				(width 0.1)
				(type default)
			)
			(layer "F.Fab")
		)
		(fp_line
			(start -0.7239 1.9939)
			(end 0.7239 1.9939)
			(stroke
				(width 0.1)
				(type default)
			)
			(layer "F.Fab")
		)
		(pad "1" smd rect
			(at 0 0 90)
			(size 1.27 1.016)
			(layers "F.Cu" "F.Mask" "F.Paste")
			(net "P12V_FAN")
		)
		(pad "2" smd rect
			(at 0 1.778 90)
			(size 1.27 1.016)
			(layers "F.Cu" "F.Mask" "F.Paste")
			(net "P12V_PUMP")
		)
		(zone
			(layer "F.Cu")
			(hatch none 0.5)
			(connect_pads
				(clearance 0)
			)
			(min_thickness 0.25)
			(keepout
				(tracks not_allowed)
				(vias allowed)
				(pads allowed)
				(copperpour not_allowed)
				(footprints allowed)
			)
			(placement
				(enabled no)
				(sheetname "")
			)
			(fill
				(thermal_gap 0.5)
				(thermal_bridge_width 0.5)
				(island_removal_mode 0)
			)
			(polygon
				(pts
					(xy 7.841234 -114.475514) (xy 8.603234 -114.475514) (xy 8.603234 -114.386614) (xy 8.603234 -113.205514)
					(xy 7.841234 -113.205514)
				)
			)
		)
	)
	(footprint ""
		(layer "F.Cu")
		(at 313.299602 -34.652458)
		(property "Reference" "Q1W6"
			(at -0.229362 -1.59512 0)
			(unlocked yes)
			(layer "F.SilkS")
			(effects
				(font
					(size 1.27 0.9652)
					(thickness 0.1524)
				)
				(justify left)
			)
		)
		(property "Value" ""
			(at 0 0 0)
			(layer "F.Fab")
			(effects
				(font
					(size 1.27 1.27)
				)
			)
		)
		(duplicate_pad_numbers_are_jumpers no)
		(fp_line
			(start 0.381 0.635)
			(end 0.381 1.27)
			(stroke
				(width 0.1524)
				(type default)
			)
			(layer "F.SilkS")
		)
		(fp_line
			(start 0.9525 -0.5715)
			(end 1.778 -0.5715)
			(stroke
				(width 0.1524)
				(type default)
			)
			(layer "F.SilkS")
		)
		(fp_line
			(start 0.9525 2.4765)
			(end 1.778 2.4765)
			(stroke
				(width 0.1524)
				(type default)
			)
			(layer "F.SilkS")
		)
		(fp_line
			(start 1.778 -0.5715)
			(end 1.778 0.3175)
			(stroke
				(width 0.1524)
				(type default)
			)
			(layer "F.SilkS")
		)
		(fp_line
			(start 1.778 2.4765)
			(end 1.778 1.5875)
			(stroke
				(width 0.1524)
				(type default)
			)
			(layer "F.SilkS")
		)
		(fp_circle
			(center -0.37846 -0.885952)
			(end -0.25146 -0.885952)
			(stroke
				(width 0.254)
				(type default)
			)
			(fill no)
			(layer "F.SilkS")
		)
		(fp_poly
			(pts
				(xy 1.778 2.4765) (xy 0.381 2.4765) (xy 0.381 -0.5715) (xy 1.778 -0.5715)
			)
			(stroke
				(width 0)
				(type default)
			)
			(fill no)
			(layer "F.CrtYd")
		)
		(fp_line
			(start 0.381 -0.5715)
			(end 0.381 2.4765)
			(stroke
				(width 0.1)
				(type default)
			)
			(layer "F.Fab")
		)
		(fp_line
			(start 0.381 2.4765)
			(end 1.778 2.4765)
			(stroke
				(width 0.1)
				(type default)
			)
			(layer "F.Fab")
		)
		(fp_line
			(start 1.778 -0.5715)
			(end 0.381 -0.5715)
			(stroke
				(width 0.1)
				(type default)
			)
			(layer "F.Fab")
		)
		(fp_line
			(start 1.778 2.4765)
			(end 1.778 -0.5715)
			(stroke
				(width 0.1)
				(type default)
			)
			(layer "F.Fab")
		)
		(fp_circle
			(center -0.37846 -0.885952)
			(end -0.25146 -0.885952)
			(stroke
				(width 0.254)
				(type default)
			)
			(fill no)
			(layer "F.Fab")
		)
		(pad "1" smd rect
			(at 0 0)
			(size 1.143 0.508)
			(layers "F.Cu" "F.Mask" "F.Paste")
			(net "FM_ADR_COMPLETE_CPU1_R")
		)
		(pad "2" smd rect
			(at 0 1.905)
			(size 1.143 0.508)
			(layers "F.Cu" "F.Mask" "F.Paste")
			(net "GND")
		)
		(pad "3" smd rect
			(at 2.159 0.9525)
			(size 1.143 0.508)
			(layers "F.Cu" "F.Mask" "F.Paste")
			(net "FM_ADR_COMPLETE_CPU1_N")
		)
	)
	(footprint ""
		(layer "F.Cu")
		(at 451.612 -25.4254 90)
		(property "Reference" "C9W13"
			(at 1.47828 0.78994 0)
			(unlocked yes)
			(layer "F.SilkS")
			(effects
				(font
					(size 0.4064 0.254)
					(thickness 0.1524)
				)
			)
		)
		(property "Value" ""
			(at 0 0 90)
			(layer "F.Fab")
			(effects
				(font
					(size 1.27 1.27)
				)
			)
		)
		(duplicate_pad_numbers_are_jumpers no)
		(fp_poly
			(pts
				(xy -0.7239 -0.2159) (xy 0.7239 -0.2159) (xy 0.7239 1.9939) (xy -0.7239 1.9939)
			)
			(stroke
				(width 0)
				(type default)
			)
			(fill no)
			(layer "F.CrtYd")
		)
		(fp_line
			(start 0.7239 -0.2159)
			(end -0.7239 -0.2159)
			(stroke
				(width 0.1)
				(type default)
			)
			(layer "F.Fab")
		)
		(fp_line
			(start -0.7239 -0.2159)
			(end -0.7239 1.9939)
			(stroke
				(width 0.1)
				(type default)
			)
			(layer "F.Fab")
		)
		(fp_line
			(start 0.7239 1.9939)
			(end 0.7239 -0.2159)
			(stroke
				(width 0.1)
				(type default)
			)
			(layer "F.Fab")
		)
		(fp_line
			(start -0.7239 1.9939)
			(end 0.7239 1.9939)
			(stroke
				(width 0.1)
				(type default)
			)
			(layer "F.Fab")
		)
		(pad "1" smd rect
			(at 0 0 90)
			(size 1.27 1.016)
			(layers "F.Cu" "F.Mask" "F.Paste")
			(net "P2V5_AUX_BMC")
		)
		(pad "2" smd rect
			(at 0 1.778 90)
			(size 1.27 1.016)
			(layers "F.Cu" "F.Mask" "F.Paste")
			(net "GND")
		)
		(zone
			(layer "F.Cu")
			(hatch none 0.5)
			(connect_pads
				(clearance 0)
			)
			(min_thickness 0.25)
			(keepout
				(tracks not_allowed)
				(vias allowed)
				(pads allowed)
				(copperpour not_allowed)
				(footprints allowed)
			)
			(placement
				(enabled no)
				(sheetname "")
			)
			(fill
				(thermal_gap 0.5)
				(thermal_bridge_width 0.5)
				(island_removal_mode 0)
			)
			(polygon
				(pts
					(xy 452.12 -24.7904) (xy 452.12 -26.0604) (xy 452.882 -26.0604) (xy 452.882 -24.7904)
				)
			)
		)
	)
)
